# Barreleye-G2_Tri-mode Expander-DVT-X01-SKU-BOM-X07-20171222_Final.xls.xlsx — Single-Sole Source Parts List (bom)
| FOXCONN TECHNOLOGY GROUP |  |  |  |  |  |  |  |  |  |  |  |  |  |  |  |  |  |
| BILL OF MATERIAL |  |  |  |  |  |  |  |  |  |  |  |  |  |  |  |  |  |
| REV OF  BOM |  | CUSTOMER | <name> |  | CUSTOMER P/N |  | PWA P/N： | PWA DESCRIPTION |  |  | PRODUCT CODE |  |  | PWA REV |  | DATE |  |
| Sourcing (Single or Sole | Critical Commodity (Y or N) | Component Class (1, 2, other) | Customer PSL (Y/N) | Item Number | Foxconn P/N | Customer P/N | Part Description | Mfr. 1 | Mfr Part # 1 | Proposed Mfr. 2 | Proposed Mfr. 2 PN | Qty | RoHS Status | Location | 2nd Source Qual Build: | Customer Comments | ODM Comments |
